(kicad_pcb
	(version 20260206)
	(generator "pcbnew")
	(generator_version "10.0")
	(general
		(thickness 1.6)
		(legacy_teardrops no)
	)
	(paper "A4")
	(title_block
		(title "panther-plus-userver — 13130-1b_20150205.brd")
		(comment 1 "Honey Badger (Wiwynn) / footprints 1403-1410 of 1509")
	)
	(layers
		(0 "F.Cu" signal "TOP")
		(4 "In1.Cu" signal "L2")
		(6 "In2.Cu" signal "L3")
		(8 "In3.Cu" signal "L4")
		(10 "In4.Cu" signal "L5")
		(12 "In5.Cu" signal "L6")
		(14 "In6.Cu" signal "L7")
		(16 "In7.Cu" signal "L8")
		(18 "In8.Cu" signal "L9")
		(20 "In9.Cu" signal "L10")
		(22 "In10.Cu" signal "L11")
		(2 "B.Cu" signal "BOTTOM")
		(9 "F.Adhes" user "F.Adhesive")
		(11 "B.Adhes" user "B.Adhesive")
		(13 "F.Paste" user "Package Geometry/Pastemask Top")
		(15 "B.Paste" user "Package Geometry/Pastemask Bottom")
		(5 "F.SilkS" user "Ref Des/Silkscreen Top")
		(7 "B.SilkS" user "Ref Des/Silkscreen Bottom")
		(1 "F.Mask" user "Board Geometry/Soldermask Top")
		(3 "B.Mask" user "Board Geometry/Soldermask Bottom")
		(17 "Dwgs.User" user "User.Drawings")
		(19 "Cmts.User" user "User.Comments")
		(21 "Eco1.User" user "User.Eco1")
		(23 "Eco2.User" user "User.Eco2")
		(25 "Edge.Cuts" user "Board Geometry/Outline")
		(27 "Margin" user)
		(31 "F.CrtYd" user "Package Geometry/Place Bound Top")
		(29 "B.CrtYd" user "Package Geometry/Place Bound Bottom")
		(35 "F.Fab" user "Ref Des/Assembly Top")
		(33 "B.Fab" user "Ref Des/Assembly Bottom")
	)
	(footprint ""
		(layer "B.Cu")
		(at 67.183 -29.7688 -90)
		(property "Reference" "C283"
			(at 0 0 90)
			(layer "B.SilkS")
			(hide yes)
			(effects
				(font
					(size 1.27 1.27)
				)
				(justify mirror)
			)
		)
		(property "Value" "SCD01U16V2KX-3GP"
			(at -1.1811 -2.7051 270)
			(unlocked yes)
			(layer "B.Fab")
			(hide yes)
			(effects
				(font
					(size 1.016 1.016)
					(thickness 0.1524)
				)
				(justify mirror)
			)
		)
		(property "Device Type" "C402H22"
			(at -1.1811 -4.2291 270)
			(unlocked yes)
			(layer "B.Fab")
			(hide yes)
			(effects
				(font
					(size 1.016 1.016)
					(thickness 0.1524)
				)
				(justify mirror)
			)
		)
		(duplicate_pad_numbers_are_jumpers no)
		(fp_rect
			(start 0.381 0.7366)
			(end -0.381 -0.7366)
			(stroke
				(width 0)
				(type default)
			)
			(fill no)
			(layer "B.CrtYd")
		)
		(fp_rect
			(start 0.381 0.7366)
			(end -0.381 -0.7366)
			(stroke
				(width 0)
				(type default)
			)
			(fill no)
			(layer "B.Fab")
		)
		(pad "1" smd custom
			(at 0 -0.4572 90)
			(size 0.1143 0.1143)
			(layers "B.Cu" "B.Mask" "B.Paste")
			(net "SATA3_RX_DN0")
			(options
				(clearance outline)
				(anchor circle)
			)
			(primitives
				(gr_poly
					(pts
						(arc
							(start -0.254 0.1778)
							(mid -0.239121 0.213721)
							(end -0.2032 0.2286)
						)
						(arc
							(start 0.2032 0.2286)
							(mid 0.239121 0.213721)
							(end 0.254 0.1778)
						)
						(arc
							(start 0.254 -0.1778)
							(mid 0.239121 -0.213721)
							(end 0.2032 -0.2286)
						)
						(arc
							(start -0.2032 -0.2286)
							(mid -0.239121 -0.213721)
							(end -0.254 -0.1778)
						)
					)
					(width 0)
					(fill yes)
				)
			)
		)
		(pad "2" smd custom
			(at 0 0.4572 90)
			(size 0.1143 0.1143)
			(layers "B.Cu" "B.Mask" "B.Paste")
			(net "SATA3_RX_C_DN0")
			(options
				(clearance outline)
				(anchor circle)
			)
			(primitives
				(gr_poly
					(pts
						(arc
							(start -0.254 0.1778)
							(mid -0.239121 0.213721)
							(end -0.2032 0.2286)
						)
						(arc
							(start 0.2032 0.2286)
							(mid 0.239121 0.213721)
							(end 0.254 0.1778)
						)
						(arc
							(start 0.254 -0.1778)
							(mid 0.239121 -0.213721)
							(end 0.2032 -0.2286)
						)
						(arc
							(start -0.2032 -0.2286)
							(mid -0.239121 -0.213721)
							(end -0.254 -0.1778)
						)
					)
					(width 0)
					(fill yes)
				)
			)
		)
	)
	(footprint ""
		(layer "B.Cu")
		(at 21.717 -12.7)
		(property "Reference" "C285"
			(at 0 0 0)
			(layer "B.SilkS")
			(hide yes)
			(effects
				(font
					(size 1.27 1.27)
				)
				(justify mirror)
			)
		)
		(property "Value" "SCD1U16V2KX-3GP"
			(at -1.1811 -2.7051 0)
			(unlocked yes)
			(layer "B.Fab")
			(hide yes)
			(effects
				(font
					(size 1.016 1.016)
					(thickness 0.1524)
				)
				(justify mirror)
			)
		)
		(property "Device Type" "C402H22"
			(at -1.1811 -4.2291 0)
			(unlocked yes)
			(layer "B.Fab")
			(hide yes)
			(effects
				(font
					(size 1.016 1.016)
					(thickness 0.1524)
				)
				(justify mirror)
			)
		)
		(duplicate_pad_numbers_are_jumpers no)
		(fp_rect
			(start 0.381 0.7366)
			(end -0.381 -0.7366)
			(stroke
				(width 0)
				(type default)
			)
			(fill no)
			(layer "B.CrtYd")
		)
		(fp_rect
			(start 0.381 0.7366)
			(end -0.381 -0.7366)
			(stroke
				(width 0)
				(type default)
			)
			(fill no)
			(layer "B.Fab")
		)
		(pad "1" smd custom
			(at 0 -0.4572 180)
			(size 0.1143 0.1143)
			(layers "B.Cu" "B.Mask" "B.Paste")
			(net "P2E_CPU_ETH10G_C_TX_DN10")
			(options
				(clearance outline)
				(anchor circle)
			)
			(primitives
				(gr_poly
					(pts
						(arc
							(start -0.254 0.1778)
							(mid -0.239121 0.213721)
							(end -0.2032 0.2286)
						)
						(arc
							(start 0.2032 0.2286)
							(mid 0.239121 0.213721)
							(end 0.254 0.1778)
						)
						(arc
							(start 0.254 -0.1778)
							(mid 0.239121 -0.213721)
							(end 0.2032 -0.2286)
						)
						(arc
							(start -0.2032 -0.2286)
							(mid -0.239121 -0.213721)
							(end -0.254 -0.1778)
						)
					)
					(width 0)
					(fill yes)
				)
			)
		)
		(pad "2" smd custom
			(at 0 0.4572 180)
			(size 0.1143 0.1143)
			(layers "B.Cu" "B.Mask" "B.Paste")
			(net "P2E_CPU_ETH10G_TX_DN10")
			(options
				(clearance outline)
				(anchor circle)
			)
			(primitives
				(gr_poly
					(pts
						(arc
							(start -0.254 0.1778)
							(mid -0.239121 0.213721)
							(end -0.2032 0.2286)
						)
						(arc
							(start 0.2032 0.2286)
							(mid 0.239121 0.213721)
							(end 0.254 0.1778)
						)
						(arc
							(start 0.254 -0.1778)
							(mid 0.239121 -0.213721)
							(end 0.2032 -0.2286)
						)
						(arc
							(start -0.2032 -0.2286)
							(mid -0.239121 -0.213721)
							(end -0.254 -0.1778)
						)
					)
					(width 0)
					(fill yes)
				)
			)
		)
	)
	(footprint ""
		(layer "B.Cu")
		(at 94.869 -28.972002 -90)
		(property "Reference" "TP51"
			(at 0 0 90)
			(layer "B.SilkS")
			(hide yes)
			(effects
				(font
					(size 1.27 1.27)
				)
				(justify mirror)
			)
		)
		(property "Value" "TPAD24"
			(at 0 -2.9972 270)
			(unlocked yes)
			(layer "B.Fab")
			(hide yes)
			(effects
				(font
					(size 1.016 1.016)
					(thickness 0.1524)
				)
				(justify mirror)
			)
		)
		(property "Device Type" "TPAD24"
			(at 0 -4.5212 270)
			(unlocked yes)
			(layer "B.Fab")
			(hide yes)
			(effects
				(font
					(size 1.016 1.016)
					(thickness 0.1524)
				)
				(justify mirror)
			)
		)
		(duplicate_pad_numbers_are_jumpers no)
		(fp_poly
			(pts
				(arc
					(start 0 -0.3048)
					(mid 0 0.3048)
					(end 0 -0.3048)
				)
			)
			(stroke
				(width 0)
				(type default)
			)
			(fill no)
			(layer "B.CrtYd")
		)
		(fp_poly
			(pts
				(arc
					(start 0 -0.6096)
					(mid 0 0.6096)
					(end 0 -0.6096)
				)
			)
			(stroke
				(width 0)
				(type default)
			)
			(fill no)
			(layer "B.Fab")
		)
		(pad "1" smd circle
			(at 0 0 90)
			(size 0.6096 0.6096)
			(layers "B.Cu" "B.Mask" "B.Paste")
			(net "TP_CPU_RSVD17")
		)
	)
	(footprint ""
		(layer "B.Cu")
		(at 141.097 -45.466 90)
		(property "Reference" "R338"
			(at 0 0 90)
			(layer "B.SilkS")
			(hide yes)
			(effects
				(font
					(size 1.27 1.27)
				)
				(justify mirror)
			)
		)
		(property "Value" "1KR2F-3-GP"
			(at -0.064008 -3.993896 90)
			(unlocked yes)
			(layer "B.Fab")
			(hide yes)
			(effects
				(font
					(size 1.016 1.016)
					(thickness 0.1524)
				)
				(justify mirror)
			)
		)
		(property "Device Type" "R402H16"
			(at -0.064008 -5.517896 90)
			(unlocked yes)
			(layer "B.Fab")
			(hide yes)
			(effects
				(font
					(size 1.016 1.016)
					(thickness 0.1524)
				)
				(justify mirror)
			)
		)
		(duplicate_pad_numbers_are_jumpers no)
		(fp_rect
			(start 0.381 0.8382)
			(end -0.381 -0.8382)
			(stroke
				(width 0)
				(type default)
			)
			(fill no)
			(layer "B.CrtYd")
		)
		(fp_rect
			(start 0.381 0.8382)
			(end -0.381 -0.8382)
			(stroke
				(width 0)
				(type default)
			)
			(fill no)
			(layer "B.Fab")
		)
		(pad "1" smd custom
			(at 0 -0.4318 270)
			(size 0.127 0.127)
			(layers "B.Cu" "B.Mask" "B.Paste")
			(net "C_NCE#")
			(options
				(clearance outline)
				(anchor circle)
			)
			(primitives
				(gr_poly
					(pts
						(arc
							(start -0.2032 0.2794)
							(mid -0.239121 0.264521)
							(end -0.254 0.2286)
						)
						(arc
							(start -0.254 -0.2286)
							(mid -0.239121 -0.264521)
							(end -0.2032 -0.2794)
						)
						(arc
							(start 0.2032 -0.2794)
							(mid 0.239121 -0.264521)
							(end 0.254 -0.2286)
						)
						(arc
							(start 0.254 0.2286)
							(mid 0.239121 0.264521)
							(end 0.2032 0.2794)
						)
					)
					(width 0)
					(fill yes)
				)
			)
		)
		(pad "2" smd custom
			(at 0 0.4318 270)
			(size 0.127 0.127)
			(layers "B.Cu" "B.Mask" "B.Paste")
			(net "GND")
			(options
				(clearance outline)
				(anchor circle)
			)
			(primitives
				(gr_poly
					(pts
						(arc
							(start -0.2032 0.2794)
							(mid -0.239121 0.264521)
							(end -0.254 0.2286)
						)
						(arc
							(start -0.254 -0.2286)
							(mid -0.239121 -0.264521)
							(end -0.2032 -0.2794)
						)
						(arc
							(start 0.2032 -0.2794)
							(mid 0.239121 -0.264521)
							(end 0.254 -0.2286)
						)
						(arc
							(start 0.254 0.2286)
							(mid 0.239121 0.264521)
							(end 0.2032 0.2794)
						)
					)
					(width 0)
					(fill yes)
				)
			)
		)
	)
	(footprint ""
		(layer "B.Cu")
		(at 30.6832 -33.1724)
		(property "Reference" "R490"
			(at 0 0 0)
			(layer "B.SilkS")
			(hide yes)
			(effects
				(font
					(size 1.27 1.27)
				)
				(justify mirror)
			)
		)
		(property "Value" "51R2F-2-GP"
			(at -1.7907 -1.1176 0)
			(unlocked yes)
			(layer "B.Fab")
			(hide yes)
			(effects
				(font
					(size 1.016 1.016)
					(thickness 0.1524)
				)
				(justify mirror)
			)
		)
		(property "Device Type" "R402H16"
			(at -1.7907 -2.6416 0)
			(unlocked yes)
			(layer "B.Fab")
			(hide yes)
			(effects
				(font
					(size 1.016 1.016)
					(thickness 0.1524)
				)
				(justify mirror)
			)
		)
		(duplicate_pad_numbers_are_jumpers no)
		(fp_rect
			(start 0.381 0.8382)
			(end -0.381 -0.8382)
			(stroke
				(width 0)
				(type default)
			)
			(fill no)
			(layer "B.CrtYd")
		)
		(fp_rect
			(start 0.381 0.8382)
			(end -0.381 -0.8382)
			(stroke
				(width 0)
				(type default)
			)
			(fill no)
			(layer "B.Fab")
		)
		(pad "1" smd custom
			(at 0 -0.4318 180)
			(size 0.127 0.127)
			(layers "B.Cu" "B.Mask" "B.Paste")
			(net "P1V0_STBY")
			(options
				(clearance outline)
				(anchor circle)
			)
			(primitives
				(gr_poly
					(pts
						(arc
							(start -0.2032 0.2794)
							(mid -0.239121 0.264521)
							(end -0.254 0.2286)
						)
						(arc
							(start -0.254 -0.2286)
							(mid -0.239121 -0.264521)
							(end -0.2032 -0.2794)
						)
						(arc
							(start 0.2032 -0.2794)
							(mid 0.239121 -0.264521)
							(end 0.254 -0.2286)
						)
						(arc
							(start 0.254 0.2286)
							(mid 0.239121 0.264521)
							(end 0.2032 0.2794)
						)
					)
					(width 0)
					(fill yes)
				)
			)
		)
		(pad "2" smd custom
			(at 0 0.4318 180)
			(size 0.127 0.127)
			(layers "B.Cu" "B.Mask" "B.Paste")
			(net "XDP_SOC_CPU_TRST#")
			(options
				(clearance outline)
				(anchor circle)
			)
			(primitives
				(gr_poly
					(pts
						(arc
							(start -0.2032 0.2794)
							(mid -0.239121 0.264521)
							(end -0.254 0.2286)
						)
						(arc
							(start -0.254 -0.2286)
							(mid -0.239121 -0.264521)
							(end -0.2032 -0.2794)
						)
						(arc
							(start 0.2032 -0.2794)
							(mid 0.239121 -0.264521)
							(end 0.254 -0.2286)
						)
						(arc
							(start 0.254 0.2286)
							(mid 0.239121 0.264521)
							(end 0.2032 0.2794)
						)
					)
					(width 0)
					(fill yes)
				)
			)
		)
	)
	(footprint ""
		(layer "B.Cu")
		(at 72.009 -24.13 90)
		(property "Reference" "PR176"
			(at 0 0 90)
			(layer "B.SilkS")
			(hide yes)
			(effects
				(font
					(size 1.27 1.27)
				)
				(justify mirror)
			)
		)
		(property "Value" "10R2F-L-GP"
			(at -1.7907 -1.1176 90)
			(unlocked yes)
			(layer "B.Fab")
			(hide yes)
			(effects
				(font
					(size 1.016 1.016)
					(thickness 0.1524)
				)
				(justify mirror)
			)
		)
		(property "Device Type" "R402H14"
			(at -1.7907 -2.6416 90)
			(unlocked yes)
			(layer "B.Fab")
			(hide yes)
			(effects
				(font
					(size 1.016 1.016)
					(thickness 0.1524)
				)
				(justify mirror)
			)
		)
		(duplicate_pad_numbers_are_jumpers no)
		(fp_rect
			(start 0.381 0.8382)
			(end -0.381 -0.8382)
			(stroke
				(width 0)
				(type default)
			)
			(fill no)
			(layer "B.CrtYd")
		)
		(fp_rect
			(start 0.381 0.8382)
			(end -0.381 -0.8382)
			(stroke
				(width 0)
				(type default)
			)
			(fill no)
			(layer "B.Fab")
		)
		(pad "1" smd custom
			(at 0 -0.4318 270)
			(size 0.127 0.127)
			(layers "B.Cu" "B.Mask" "B.Paste")
			(net "VR_AVIN_P1V8_STBY")
			(options
				(clearance outline)
				(anchor circle)
			)
			(primitives
				(gr_poly
					(pts
						(arc
							(start -0.2032 0.2794)
							(mid -0.239121 0.264521)
							(end -0.254 0.2286)
						)
						(arc
							(start -0.254 -0.2286)
							(mid -0.239121 -0.264521)
							(end -0.2032 -0.2794)
						)
						(arc
							(start 0.2032 -0.2794)
							(mid 0.239121 -0.264521)
							(end 0.254 -0.2286)
						)
						(arc
							(start 0.254 0.2286)
							(mid 0.239121 0.264521)
							(end 0.2032 0.2794)
						)
					)
					(width 0)
					(fill yes)
				)
			)
		)
		(pad "2" smd custom
			(at 0 0.4318 270)
			(size 0.127 0.127)
			(layers "B.Cu" "B.Mask" "B.Paste")
			(net "VR_PVIN_P1V8_STBY")
			(options
				(clearance outline)
				(anchor circle)
			)
			(primitives
				(gr_poly
					(pts
						(arc
							(start -0.2032 0.2794)
							(mid -0.239121 0.264521)
							(end -0.254 0.2286)
						)
						(arc
							(start -0.254 -0.2286)
							(mid -0.239121 -0.264521)
							(end -0.2032 -0.2794)
						)
						(arc
							(start 0.2032 -0.2794)
							(mid 0.239121 -0.264521)
							(end 0.254 -0.2286)
						)
						(arc
							(start 0.254 0.2286)
							(mid 0.239121 0.264521)
							(end 0.2032 0.2794)
						)
					)
					(width 0)
					(fill yes)
				)
			)
		)
	)
	(footprint ""
		(layer "B.Cu")
		(at 31.496 -44.45 90)
		(property "Reference" "PC138"
			(at 0 0 90)
			(layer "B.SilkS")
			(hide yes)
			(effects
				(font
					(size 1.27 1.27)
				)
				(justify mirror)
			)
		)
		(property "Value" "SCD1U10V2KX-5GP"
			(at -1.8923 -1.2065 90)
			(unlocked yes)
			(layer "B.Fab")
			(hide yes)
			(effects
				(font
					(size 1.016 1.016)
					(thickness 0.1524)
				)
				(justify mirror)
			)
		)
		(property "Device Type" "C402H22"
			(at -1.8923 -2.7305 90)
			(unlocked yes)
			(layer "B.Fab")
			(hide yes)
			(effects
				(font
					(size 1.016 1.016)
					(thickness 0.1524)
				)
				(justify mirror)
			)
		)
		(duplicate_pad_numbers_are_jumpers no)
		(fp_rect
			(start 0.381 0.7366)
			(end -0.381 -0.7366)
			(stroke
				(width 0)
				(type default)
			)
			(fill no)
			(layer "B.CrtYd")
		)
		(fp_rect
			(start 0.381 0.7366)
			(end -0.381 -0.7366)
			(stroke
				(width 0)
				(type default)
			)
			(fill no)
			(layer "B.Fab")
		)
		(pad "1" smd custom
			(at 0 -0.4572 270)
			(size 0.1143 0.1143)
			(layers "B.Cu" "B.Mask" "B.Paste")
			(net "P1V5_STBY_OUT")
			(options
				(clearance outline)
				(anchor circle)
			)
			(primitives
				(gr_poly
					(pts
						(arc
							(start -0.254 0.1778)
							(mid -0.239121 0.213721)
							(end -0.2032 0.2286)
						)
						(arc
							(start 0.2032 0.2286)
							(mid 0.239121 0.213721)
							(end 0.254 0.1778)
						)
						(arc
							(start 0.254 -0.1778)
							(mid 0.239121 -0.213721)
							(end 0.2032 -0.2286)
						)
						(arc
							(start -0.2032 -0.2286)
							(mid -0.239121 -0.213721)
							(end -0.254 -0.1778)
						)
					)
					(width 0)
					(fill yes)
				)
			)
		)
		(pad "2" smd custom
			(at 0 0.4572 270)
			(size 0.1143 0.1143)
			(layers "B.Cu" "B.Mask" "B.Paste")
			(net "GND")
			(options
				(clearance outline)
				(anchor circle)
			)
			(primitives
				(gr_poly
					(pts
						(arc
							(start -0.254 0.1778)
							(mid -0.239121 0.213721)
							(end -0.2032 0.2286)
						)
						(arc
							(start 0.2032 0.2286)
							(mid 0.239121 0.213721)
							(end 0.254 0.1778)
						)
						(arc
							(start 0.254 -0.1778)
							(mid 0.239121 -0.213721)
							(end 0.2032 -0.2286)
						)
						(arc
							(start -0.2032 -0.2286)
							(mid -0.239121 -0.213721)
							(end -0.254 -0.1778)
						)
					)
					(width 0)
					(fill yes)
				)
			)
		)
	)
	(footprint ""
		(layer "B.Cu")
		(at 69.6214 -23.4188 -90)
		(property "Reference" "PC127"
			(at 0 0 90)
			(layer "B.SilkS")
			(hide yes)
			(effects
				(font
					(size 1.27 1.27)
				)
				(justify mirror)
			)
		)
		(property "Value" "SC1U16V3KX-5GP"
			(at 0.0254 -2.0193 270)
			(unlocked yes)
			(layer "B.Fab")
			(hide yes)
			(effects
				(font
					(size 1.016 1.016)
					(thickness 0.1524)
				)
				(justify mirror)
			)
		)
		(property "Device Type" "C603H36"
			(at 0.0254 -3.5433 270)
			(unlocked yes)
			(layer "B.Fab")
			(hide yes)
			(effects
				(font
					(size 1.016 1.016)
					(thickness 0.1524)
				)
				(justify mirror)
			)
		)
		(duplicate_pad_numbers_are_jumpers no)
		(fp_line
			(start 0.4064 0)
			(end -0.4064 0)
			(stroke
				(width 0.2286)
				(type default)
			)
			(layer "B.SilkS")
		)
		(fp_rect
			(start 0.635 1.1811)
			(end -0.635 -1.1811)
			(stroke
				(width 0)
				(type default)
			)
			(fill no)
			(layer "B.CrtYd")
		)
		(fp_rect
			(start 0.635 1.1811)
			(end -0.635 -1.1811)
			(stroke
				(width 0)
				(type default)
			)
			(fill no)
			(layer "B.Fab")
		)
		(pad "1" smd custom
			(at 0 -0.6604 90)
			(size 0.19685 0.19685)
			(layers "B.Cu" "B.Mask" "B.Paste")
			(net "VR_AVIN_P1V8_STBY")
			(options
				(clearance outline)
				(anchor circle)
			)
			(primitives
				(gr_poly
					(pts
						(arc
							(start 0.508 0.2921)
							(mid 0.478242 0.363942)
							(end 0.4064 0.3937)
						)
						(arc
							(start -0.4064 0.3937)
							(mid -0.478242 0.363942)
							(end -0.508 0.2921)
						)
						(arc
							(start -0.508 -0.2921)
							(mid -0.478242 -0.363942)
							(end -0.4064 -0.3937)
						)
						(arc
							(start 0.4064 -0.3937)
							(mid 0.478242 -0.363942)
							(end 0.508 -0.2921)
						)
					)
					(width 0)
					(fill yes)
				)
			)
		)
		(pad "2" smd custom
			(at 0 0.6604 90)
			(size 0.19685 0.19685)
			(layers "B.Cu" "B.Mask" "B.Paste")
			(net "AGND_P1V8_STBY")
			(options
				(clearance outline)
				(anchor circle)
			)
			(primitives
				(gr_poly
					(pts
						(arc
							(start 0.508 0.2921)
							(mid 0.478242 0.363942)
							(end 0.4064 0.3937)
						)
						(arc
							(start -0.4064 0.3937)
							(mid -0.478242 0.363942)
							(end -0.508 0.2921)
						)
						(arc
							(start -0.508 -0.2921)
							(mid -0.478242 -0.363942)
							(end -0.4064 -0.3937)
						)
						(arc
							(start 0.4064 -0.3937)
							(mid 0.478242 -0.363942)
							(end 0.508 -0.2921)
						)
					)
					(width 0)
					(fill yes)
				)
			)
		)
	)
)
